(kicad_pcb
	(version 20260206)
	(generator "pcbnew")
	(generator_version "10.0")
	(general
		(thickness 1.6)
		(legacy_teardrops no)
	)
	(paper "A4")
	(title_block
		(title "peb — Lightning_PEB_BRD.brd")
		(comment 1 "Lightning (Wiwynn / Facebook NVMe JBOF) / footprints 1659-1666 of 2563")
	)
	(layers
		(0 "F.Cu" signal "TOP")
		(4 "In1.Cu" signal "L2GND")
		(6 "In2.Cu" signal "L3")
		(8 "In3.Cu" signal "L4VCC")
		(10 "In4.Cu" signal "L5VCC")
		(12 "In5.Cu" signal "L6")
		(14 "In6.Cu" signal "L7GND")
		(2 "B.Cu" signal "BOTTOM")
		(9 "F.Adhes" user "F.Adhesive")
		(11 "B.Adhes" user "B.Adhesive")
		(13 "F.Paste" user "Package Geometry/Pastemask Top")
		(15 "B.Paste" user "Package Geometry/Pastemask Bottom")
		(5 "F.SilkS" user "Ref Des/Silkscreen Top")
		(7 "B.SilkS" user "Ref Des/Silkscreen Bottom")
		(1 "F.Mask" user "Board Geometry/Soldermask Top")
		(3 "B.Mask" user "Board Geometry/Soldermask Bottom")
		(17 "Dwgs.User" user "User.Drawings")
		(19 "Cmts.User" user "User.Comments")
		(21 "Eco1.User" user "User.Eco1")
		(23 "Eco2.User" user "User.Eco2")
		(25 "Edge.Cuts" user "Board Geometry/Outline")
		(27 "Margin" user)
		(31 "F.CrtYd" user "Package Geometry/Place Bound Top")
		(29 "B.CrtYd" user "Package Geometry/Place Bound Bottom")
		(35 "F.Fab" user "Ref Des/Assembly Top")
		(33 "B.Fab" user "Ref Des/Assembly Bottom")
	)
	(footprint ""
		(layer "B.Cu")
		(at 51.2572 -113.157)
		(property "Reference" "R314"
			(at 0 0 0)
			(layer "B.SilkS")
			(hide yes)
			(effects
				(font
					(size 1.27 1.27)
				)
				(justify mirror)
			)
		)
		(property "Value" "4K7R2F-GP"
			(at -0.064008 -3.993896 0)
			(unlocked yes)
			(layer "B.Fab")
			(hide yes)
			(effects
				(font
					(size 1.016 1.016)
					(thickness 0.1524)
				)
				(justify mirror)
			)
		)
		(property "Device Type" "R402H16"
			(at -0.064008 -5.517896 0)
			(unlocked yes)
			(layer "B.Fab")
			(hide yes)
			(effects
				(font
					(size 1.016 1.016)
					(thickness 0.1524)
				)
				(justify mirror)
			)
		)
		(duplicate_pad_numbers_are_jumpers no)
		(fp_line
			(start -0.508 -0.9398)
			(end 0.508 -0.9398)
			(stroke
				(width 0.1524)
				(type default)
			)
			(layer "B.SilkS")
		)
		(fp_line
			(start 0.508 -0.9398)
			(end 0.508 0.9398)
			(stroke
				(width 0.1524)
				(type default)
			)
			(layer "B.SilkS")
		)
		(fp_rect
			(start 0.508 0.9398)
			(end -0.508 -0.9398)
			(stroke
				(width 0)
				(type default)
			)
			(fill no)
			(layer "B.CrtYd")
		)
		(fp_rect
			(start 0.508 0.9398)
			(end -0.508 -0.9398)
			(stroke
				(width 0)
				(type default)
			)
			(fill no)
			(layer "B.Fab")
		)
		(pad "1" smd custom
			(at 0 -0.4445 180)
			(size 0.1397 0.1397)
			(layers "B.Cu" "B.Mask" "B.Paste")
			(net "BMC_I2C10_8536_SDA")
			(options
				(clearance outline)
				(anchor circle)
			)
			(primitives
				(gr_poly
					(pts
						(arc
							(start -0.1778 0.2794)
							(mid -0.249642 0.249642)
							(end -0.2794 0.1778)
						)
						(arc
							(start -0.2794 -0.1778)
							(mid -0.249642 -0.249642)
							(end -0.1778 -0.2794)
						)
						(arc
							(start 0.1778 -0.2794)
							(mid 0.249642 -0.249642)
							(end 0.2794 -0.1778)
						)
						(arc
							(start 0.2794 0.1778)
							(mid 0.249642 0.249642)
							(end 0.1778 0.2794)
						)
					)
					(width 0)
					(fill yes)
				)
			)
		)
		(pad "2" smd custom
			(at 0 0.4445 180)
			(size 0.1397 0.1397)
			(layers "B.Cu" "B.Mask" "B.Paste")
			(net "P3V3_STBY")
			(options
				(clearance outline)
				(anchor circle)
			)
			(primitives
				(gr_poly
					(pts
						(arc
							(start -0.1778 0.2794)
							(mid -0.249642 0.249642)
							(end -0.2794 0.1778)
						)
						(arc
							(start -0.2794 -0.1778)
							(mid -0.249642 -0.249642)
							(end -0.1778 -0.2794)
						)
						(arc
							(start 0.1778 -0.2794)
							(mid 0.249642 -0.249642)
							(end 0.2794 -0.1778)
						)
						(arc
							(start 0.2794 0.1778)
							(mid 0.249642 0.249642)
							(end 0.1778 0.2794)
						)
					)
					(width 0)
					(fill yes)
				)
			)
		)
	)
	(footprint ""
		(layer "B.Cu")
		(at 209.839052 -3.887216)
		(property "Reference" "R3713"
			(at 0 0 0)
			(layer "B.SilkS")
			(hide yes)
			(effects
				(font
					(size 1.27 1.27)
				)
				(justify mirror)
			)
		)
		(property "Value" "1KR2F-3-GP"
			(at -0.064008 -3.993896 0)
			(unlocked yes)
			(layer "B.Fab")
			(hide yes)
			(effects
				(font
					(size 1.016 1.016)
					(thickness 0.1524)
				)
				(justify mirror)
			)
		)
		(property "Device Type" "R402H16"
			(at -0.064008 -5.517896 0)
			(unlocked yes)
			(layer "B.Fab")
			(hide yes)
			(effects
				(font
					(size 1.016 1.016)
					(thickness 0.1524)
				)
				(justify mirror)
			)
		)
		(duplicate_pad_numbers_are_jumpers no)
		(fp_line
			(start -0.508 -0.9398)
			(end 0.508 -0.9398)
			(stroke
				(width 0.1524)
				(type default)
			)
			(layer "B.SilkS")
		)
		(fp_line
			(start 0.508 -0.9398)
			(end 0.508 0.9398)
			(stroke
				(width 0.1524)
				(type default)
			)
			(layer "B.SilkS")
		)
		(fp_rect
			(start 0.508 0.9398)
			(end -0.508 -0.9398)
			(stroke
				(width 0)
				(type default)
			)
			(fill no)
			(layer "B.CrtYd")
		)
		(fp_rect
			(start 0.508 0.9398)
			(end -0.508 -0.9398)
			(stroke
				(width 0)
				(type default)
			)
			(fill no)
			(layer "B.Fab")
		)
		(pad "1" smd custom
			(at 0 -0.4445 180)
			(size 0.1397 0.1397)
			(layers "B.Cu" "B.Mask" "B.Paste")
			(net "HOST7_RST_N")
			(options
				(clearance outline)
				(anchor circle)
			)
			(primitives
				(gr_poly
					(pts
						(arc
							(start -0.1778 0.2794)
							(mid -0.249642 0.249642)
							(end -0.2794 0.1778)
						)
						(arc
							(start -0.2794 -0.1778)
							(mid -0.249642 -0.249642)
							(end -0.1778 -0.2794)
						)
						(arc
							(start 0.1778 -0.2794)
							(mid 0.249642 -0.249642)
							(end 0.2794 -0.1778)
						)
						(arc
							(start 0.2794 0.1778)
							(mid 0.249642 0.249642)
							(end 0.1778 0.2794)
						)
					)
					(width 0)
					(fill yes)
				)
			)
		)
		(pad "2" smd custom
			(at 0 0.4445 180)
			(size 0.1397 0.1397)
			(layers "B.Cu" "B.Mask" "B.Paste")
			(net "P3V3_STBY")
			(options
				(clearance outline)
				(anchor circle)
			)
			(primitives
				(gr_poly
					(pts
						(arc
							(start -0.1778 0.2794)
							(mid -0.249642 0.249642)
							(end -0.2794 0.1778)
						)
						(arc
							(start -0.2794 -0.1778)
							(mid -0.249642 -0.249642)
							(end -0.1778 -0.2794)
						)
						(arc
							(start 0.1778 -0.2794)
							(mid 0.249642 -0.249642)
							(end 0.2794 -0.1778)
						)
						(arc
							(start 0.2794 0.1778)
							(mid 0.249642 0.249642)
							(end 0.1778 0.2794)
						)
					)
					(width 0)
					(fill yes)
				)
			)
		)
	)
	(footprint ""
		(layer "B.Cu")
		(at 153.396696 -33.541462 180)
		(property "Reference" "C222"
			(at 0 0 0)
			(layer "B.SilkS")
			(hide yes)
			(effects
				(font
					(size 1.27 1.27)
				)
				(justify mirror)
			)
		)
		(property "Value" "SCD1U10V2KX-5GP"
			(at -1.1811 -2.7051 180)
			(unlocked yes)
			(layer "B.Fab")
			(hide yes)
			(effects
				(font
					(size 1.016 1.016)
					(thickness 0.1524)
				)
				(justify mirror)
			)
		)
		(property "Device Type" "C402H22"
			(at -1.1811 -4.2291 180)
			(unlocked yes)
			(layer "B.Fab")
			(hide yes)
			(effects
				(font
					(size 1.016 1.016)
					(thickness 0.1524)
				)
				(justify mirror)
			)
		)
		(duplicate_pad_numbers_are_jumpers no)
		(fp_rect
			(start 0.4318 0.9525)
			(end -0.4318 -0.9525)
			(stroke
				(width 0)
				(type default)
			)
			(fill no)
			(layer "B.CrtYd")
		)
		(fp_rect
			(start 0.4318 0.9525)
			(end -0.4318 -0.9525)
			(stroke
				(width 0)
				(type default)
			)
			(fill no)
			(layer "B.Fab")
		)
		(pad "1" smd custom
			(at 0 -0.4445)
			(size 0.1524 0.1524)
			(layers "B.Cu" "B.Mask" "B.Paste")
			(net "GND")
			(options
				(clearance outline)
				(anchor circle)
			)
			(primitives
				(gr_poly
					(pts
						(arc
							(start 0.3048 0.2032)
							(mid 0.275042 0.275042)
							(end 0.2032 0.3048)
						)
						(arc
							(start -0.2032 0.3048)
							(mid -0.275042 0.275042)
							(end -0.3048 0.2032)
						)
						(arc
							(start -0.3048 -0.2032)
							(mid -0.275042 -0.275042)
							(end -0.2032 -0.3048)
						)
						(arc
							(start 0.2032 -0.3048)
							(mid 0.275042 -0.275042)
							(end 0.3048 -0.2032)
						)
					)
					(width 0)
					(fill yes)
				)
			)
		)
		(pad "2" smd custom
			(at 0 0.4445)
			(size 0.1524 0.1524)
			(layers "B.Cu" "B.Mask" "B.Paste")
			(net "P3V3_STBY")
			(options
				(clearance outline)
				(anchor circle)
			)
			(primitives
				(gr_poly
					(pts
						(arc
							(start 0.3048 0.2032)
							(mid 0.275042 0.275042)
							(end 0.2032 0.3048)
						)
						(arc
							(start -0.2032 0.3048)
							(mid -0.275042 0.275042)
							(end -0.3048 0.2032)
						)
						(arc
							(start -0.3048 -0.2032)
							(mid -0.275042 -0.275042)
							(end -0.2032 -0.3048)
						)
						(arc
							(start 0.2032 -0.3048)
							(mid 0.275042 -0.275042)
							(end 0.3048 -0.2032)
						)
					)
					(width 0)
					(fill yes)
				)
			)
		)
	)
	(footprint ""
		(layer "B.Cu")
		(at 48.5902 -104.5464 90)
		(property "Reference" "U39"
			(at 0 0 90)
			(layer "B.SilkS")
			(hide yes)
			(effects
				(font
					(size 1.27 1.27)
				)
				(justify mirror)
			)
		)
		(property "Value" "2N7002DW-7F-GP"
			(at 2.3622 -8.2042 90)
			(unlocked yes)
			(layer "B.Fab")
			(hide yes)
			(effects
				(font
					(size 1.016 1.016)
					(thickness 0.1524)
				)
				(justify mirror)
			)
		)
		(property "Device Type" "SOT-363H44"
			(at 2.3622 -10.1092 90)
			(unlocked yes)
			(layer "B.Fab")
			(hide yes)
			(effects
				(font
					(size 1.016 1.016)
					(thickness 0.1524)
				)
				(justify mirror)
			)
		)
		(duplicate_pad_numbers_are_jumpers no)
		(fp_line
			(start 1.4478 -1.7018)
			(end 1.4478 1.7018)
			(stroke
				(width 0.1524)
				(type default)
			)
			(layer "B.SilkS")
		)
		(fp_line
			(start -1.4478 -1.7018)
			(end 1.4478 -1.7018)
			(stroke
				(width 0.1524)
				(type default)
			)
			(layer "B.SilkS")
		)
		(fp_line
			(start 1.27 1.524)
			(end 1.27 0.6604)
			(stroke
				(width 0.4826)
				(type default)
			)
			(layer "B.SilkS")
		)
		(fp_line
			(start 1.4478 1.7018)
			(end -1.4478 1.7018)
			(stroke
				(width 0.1524)
				(type default)
			)
			(layer "B.SilkS")
		)
		(fp_line
			(start -1.4478 1.7018)
			(end -1.4478 -1.7018)
			(stroke
				(width 0.1524)
				(type default)
			)
			(layer "B.SilkS")
		)
		(fp_poly
			(pts
				(xy 1.524 -1.778) (xy -1.524 -1.778) (xy -1.524 1.778) (xy 1.524 1.778)
			)
			(stroke
				(width 0)
				(type default)
			)
			(fill no)
			(layer "B.CrtYd")
		)
		(fp_poly
			(pts
				(xy 1.524 -1.778) (xy -1.524 -1.778) (xy -1.524 1.778) (xy 1.524 1.778)
			)
			(stroke
				(width 0)
				(type default)
			)
			(fill no)
			(layer "B.Fab")
		)
		(pad "1" smd rect
			(at 0.65024 0.9398 270)
			(size 0.4064 1.016)
			(layers "B.Cu" "B.Mask" "B.Paste")
			(net "BMC_I2C14_MINI8_SCL_S")
		)
		(pad "2" smd rect
			(at 0 0.9398 270)
			(size 0.4064 1.016)
			(layers "B.Cu" "B.Mask" "B.Paste")
			(net "I2C8_LS_G2")
		)
		(pad "3" smd rect
			(at -0.65024 0.9398 270)
			(size 0.4064 1.016)
			(layers "B.Cu" "B.Mask" "B.Paste")
			(net "BMC_I2C14_MINI8_SDA")
		)
		(pad "4" smd rect
			(at -0.65024 -0.9398 270)
			(size 0.4064 1.016)
			(layers "B.Cu" "B.Mask" "B.Paste")
			(net "BMC_I2C14_MINI8_SDA_S")
		)
		(pad "5" smd rect
			(at 0 -0.9398 270)
			(size 0.4064 1.016)
			(layers "B.Cu" "B.Mask" "B.Paste")
			(net "I2C8_LS_G1")
		)
		(pad "6" smd rect
			(at 0.65024 -0.9398 270)
			(size 0.4064 1.016)
			(layers "B.Cu" "B.Mask" "B.Paste")
			(net "BMC_I2C14_MINI8_SCL")
		)
	)
	(footprint ""
		(layer "B.Cu")
		(at 336.804 -63.5 90)
		(property "Reference" "PC188"
			(at 0 0 90)
			(layer "B.SilkS")
			(hide yes)
			(effects
				(font
					(size 1.27 1.27)
				)
				(justify mirror)
			)
		)
		(property "Value" "SC470P50V2KX-3GP"
			(at -1.1811 -2.7051 90)
			(unlocked yes)
			(layer "B.Fab")
			(hide yes)
			(effects
				(font
					(size 1.016 1.016)
					(thickness 0.1524)
				)
				(justify mirror)
			)
		)
		(property "Device Type" "C402H22"
			(at -1.1811 -4.2291 90)
			(unlocked yes)
			(layer "B.Fab")
			(hide yes)
			(effects
				(font
					(size 1.016 1.016)
					(thickness 0.1524)
				)
				(justify mirror)
			)
		)
		(duplicate_pad_numbers_are_jumpers no)
		(fp_rect
			(start 0.4318 0.9525)
			(end -0.4318 -0.9525)
			(stroke
				(width 0)
				(type default)
			)
			(fill no)
			(layer "B.CrtYd")
		)
		(fp_rect
			(start 0.4318 0.9525)
			(end -0.4318 -0.9525)
			(stroke
				(width 0)
				(type default)
			)
			(fill no)
			(layer "B.Fab")
		)
		(pad "1" smd custom
			(at 0 -0.4445 270)
			(size 0.1524 0.1524)
			(layers "B.Cu" "B.Mask" "B.Paste")
			(net "P0V9_E_SNB")
			(options
				(clearance outline)
				(anchor circle)
			)
			(primitives
				(gr_poly
					(pts
						(arc
							(start 0.3048 0.2032)
							(mid 0.275042 0.275042)
							(end 0.2032 0.3048)
						)
						(arc
							(start -0.2032 0.3048)
							(mid -0.275042 0.275042)
							(end -0.3048 0.2032)
						)
						(arc
							(start -0.3048 -0.2032)
							(mid -0.275042 -0.275042)
							(end -0.2032 -0.3048)
						)
						(arc
							(start 0.2032 -0.3048)
							(mid 0.275042 -0.275042)
							(end 0.3048 -0.2032)
						)
					)
					(width 0)
					(fill yes)
				)
			)
		)
		(pad "2" smd custom
			(at 0 0.4445 270)
			(size 0.1524 0.1524)
			(layers "B.Cu" "B.Mask" "B.Paste")
			(net "GND")
			(options
				(clearance outline)
				(anchor circle)
			)
			(primitives
				(gr_poly
					(pts
						(arc
							(start 0.3048 0.2032)
							(mid 0.275042 0.275042)
							(end 0.2032 0.3048)
						)
						(arc
							(start -0.2032 0.3048)
							(mid -0.275042 0.275042)
							(end -0.3048 0.2032)
						)
						(arc
							(start -0.3048 -0.2032)
							(mid -0.275042 -0.275042)
							(end -0.2032 -0.3048)
						)
						(arc
							(start 0.2032 -0.3048)
							(mid 0.275042 -0.275042)
							(end 0.3048 -0.2032)
						)
					)
					(width 0)
					(fill yes)
				)
			)
		)
	)
	(footprint ""
		(layer "B.Cu")
		(at 159.258 -88.4174 180)
		(property "Reference" "C712"
			(at 0 0 0)
			(layer "B.SilkS")
			(hide yes)
			(effects
				(font
					(size 1.27 1.27)
				)
				(justify mirror)
			)
		)
		(property "Value" "SCD1U10V2KX-5GP"
			(at -1.1811 -2.7051 180)
			(unlocked yes)
			(layer "B.Fab")
			(hide yes)
			(effects
				(font
					(size 1.016 1.016)
					(thickness 0.1524)
				)
				(justify mirror)
			)
		)
		(property "Device Type" "C402H22"
			(at -1.1811 -4.2291 180)
			(unlocked yes)
			(layer "B.Fab")
			(hide yes)
			(effects
				(font
					(size 1.016 1.016)
					(thickness 0.1524)
				)
				(justify mirror)
			)
		)
		(duplicate_pad_numbers_are_jumpers no)
		(fp_rect
			(start 0.4318 0.9525)
			(end -0.4318 -0.9525)
			(stroke
				(width 0)
				(type default)
			)
			(fill no)
			(layer "B.CrtYd")
		)
		(fp_rect
			(start 0.4318 0.9525)
			(end -0.4318 -0.9525)
			(stroke
				(width 0)
				(type default)
			)
			(fill no)
			(layer "B.Fab")
		)
		(pad "1" smd custom
			(at 0 -0.4445)
			(size 0.1524 0.1524)
			(layers "B.Cu" "B.Mask" "B.Paste")
			(net "P1V8_CLKGEN")
			(options
				(clearance outline)
				(anchor circle)
			)
			(primitives
				(gr_poly
					(pts
						(arc
							(start 0.3048 0.2032)
							(mid 0.275042 0.275042)
							(end 0.2032 0.3048)
						)
						(arc
							(start -0.2032 0.3048)
							(mid -0.275042 0.275042)
							(end -0.3048 0.2032)
						)
						(arc
							(start -0.3048 -0.2032)
							(mid -0.275042 -0.275042)
							(end -0.2032 -0.3048)
						)
						(arc
							(start 0.2032 -0.3048)
							(mid 0.275042 -0.275042)
							(end 0.3048 -0.2032)
						)
					)
					(width 0)
					(fill yes)
				)
			)
		)
		(pad "2" smd custom
			(at 0 0.4445)
			(size 0.1524 0.1524)
			(layers "B.Cu" "B.Mask" "B.Paste")
			(net "GND")
			(options
				(clearance outline)
				(anchor circle)
			)
			(primitives
				(gr_poly
					(pts
						(arc
							(start 0.3048 0.2032)
							(mid 0.275042 0.275042)
							(end 0.2032 0.3048)
						)
						(arc
							(start -0.2032 0.3048)
							(mid -0.275042 0.275042)
							(end -0.3048 0.2032)
						)
						(arc
							(start -0.3048 -0.2032)
							(mid -0.275042 -0.275042)
							(end -0.2032 -0.3048)
						)
						(arc
							(start 0.2032 -0.3048)
							(mid 0.275042 -0.275042)
							(end 0.3048 -0.2032)
						)
					)
					(width 0)
					(fill yes)
				)
			)
		)
	)
	(footprint ""
		(layer "B.Cu")
		(at 20.909788 -142.948406 -90)
		(property "Reference" "R538"
			(at 0 0 90)
			(layer "B.SilkS")
			(hide yes)
			(effects
				(font
					(size 1.27 1.27)
				)
				(justify mirror)
			)
		)
		(property "Value" "0R2J-2-GP"
			(at -0.064008 -3.993896 270)
			(unlocked yes)
			(layer "B.Fab")
			(hide yes)
			(effects
				(font
					(size 1.016 1.016)
					(thickness 0.1524)
				)
				(justify mirror)
			)
		)
		(property "Device Type" "R402H16"
			(at -0.064008 -5.517896 270)
			(unlocked yes)
			(layer "B.Fab")
			(hide yes)
			(effects
				(font
					(size 1.016 1.016)
					(thickness 0.1524)
				)
				(justify mirror)
			)
		)
		(duplicate_pad_numbers_are_jumpers no)
		(fp_line
			(start -0.508 -0.9398)
			(end 0.508 -0.9398)
			(stroke
				(width 0.1524)
				(type default)
			)
			(layer "B.SilkS")
		)
		(fp_line
			(start 0.508 -0.9398)
			(end 0.508 0.9398)
			(stroke
				(width 0.1524)
				(type default)
			)
			(layer "B.SilkS")
		)
		(fp_rect
			(start 0.508 0.9398)
			(end -0.508 -0.9398)
			(stroke
				(width 0)
				(type default)
			)
			(fill no)
			(layer "B.CrtYd")
		)
		(fp_rect
			(start 0.508 0.9398)
			(end -0.508 -0.9398)
			(stroke
				(width 0)
				(type default)
			)
			(fill no)
			(layer "B.Fab")
		)
		(pad "1" smd custom
			(at 0 -0.4445 90)
			(size 0.1397 0.1397)
			(layers "B.Cu" "B.Mask" "B.Paste")
			(net "RST_BMC_EXTRST_N_R")
			(options
				(clearance outline)
				(anchor circle)
			)
			(primitives
				(gr_poly
					(pts
						(arc
							(start -0.1778 0.2794)
							(mid -0.249642 0.249642)
							(end -0.2794 0.1778)
						)
						(arc
							(start -0.2794 -0.1778)
							(mid -0.249642 -0.249642)
							(end -0.1778 -0.2794)
						)
						(arc
							(start 0.1778 -0.2794)
							(mid 0.249642 -0.249642)
							(end 0.2794 -0.1778)
						)
						(arc
							(start 0.2794 0.1778)
							(mid 0.249642 0.249642)
							(end 0.1778 0.2794)
						)
					)
					(width 0)
					(fill yes)
				)
			)
		)
		(pad "2" smd custom
			(at 0 0.4445 90)
			(size 0.1397 0.1397)
			(layers "B.Cu" "B.Mask" "B.Paste")
			(net "RST_BMC_EXTRST_N")
			(options
				(clearance outline)
				(anchor circle)
			)
			(primitives
				(gr_poly
					(pts
						(arc
							(start -0.1778 0.2794)
							(mid -0.249642 0.249642)
							(end -0.2794 0.1778)
						)
						(arc
							(start -0.2794 -0.1778)
							(mid -0.249642 -0.249642)
							(end -0.1778 -0.2794)
						)
						(arc
							(start 0.1778 -0.2794)
							(mid 0.249642 -0.249642)
							(end 0.2794 -0.1778)
						)
						(arc
							(start 0.2794 0.1778)
							(mid 0.249642 0.249642)
							(end 0.1778 0.2794)
						)
					)
					(width 0)
					(fill yes)
				)
			)
		)
	)
	(footprint ""
		(layer "B.Cu")
		(at 227.2919 -28.46324)
		(property "Reference" "TP309"
			(at 0 0 0)
			(layer "B.SilkS")
			(hide yes)
			(effects
				(font
					(size 1.27 1.27)
				)
				(justify mirror)
			)
		)
		(property "Value" "TPAD28-2-GP"
			(at 0.0127 -1.6637 0)
			(unlocked yes)
			(layer "B.Fab")
			(hide yes)
			(effects
				(font
					(size 1.016 1.016)
					(thickness 0.1524)
				)
				(justify mirror)
			)
		)
		(property "Device Type" "TPAD28"
			(at 0.0127 -3.1877 0)
			(unlocked yes)
			(layer "B.Fab")
			(hide yes)
			(effects
				(font
					(size 1.016 1.016)
					(thickness 0.1524)
				)
				(justify mirror)
			)
		)
		(duplicate_pad_numbers_are_jumpers no)
		(fp_poly
			(pts
				(arc
					(start 0.3556 0)
					(mid -0.3556 0)
					(end 0.3556 0)
				)
			)
			(stroke
				(width 0)
				(type default)
			)
			(fill no)
			(layer "B.CrtYd")
		)
		(fp_poly
			(pts
				(arc
					(start 0.6096 0)
					(mid -0.6096 0)
					(end 0.6096 0)
				)
			)
			(stroke
				(width 0)
				(type default)
			)
			(fill no)
			(layer "B.Fab")
		)
		(pad "1" smd circle
			(at 0 0 180)
			(size 0.7112 0.7112)
			(layers "B.Cu" "B.Mask" "B.Paste")
			(net "LBI_DATA13_R")
		)
	)
)
